# S9S_MB_2U (Grand Teton) — schematic netlist excerpt (pin names and nets, part order shuffled) for the footprints in the layout excerpt that follows; sources: Cadence DE-HDL packaged netlist, KiCad conversion of 03242023_DA0F0TMBIJ0_F0T_Motherboard_J_brd_V01_OCP.brd

R1461  Q_RES  0 5% CHIP  pkg 0402LF  page 185 : A = FM_EUP_LOT6_N ; B = FM_SUSACK_N
R917  Q_RES  0 5% CHIP  pkg 0402LF  page 185 : A = SPI_PCH_IO3 ; B = SPI_SYS_HOLD_IO3

(kicad_pcb
	(version 20260206)
	(generator "pcbnew")
	(generator_version "10.0")
	(general
		(thickness 1.6)
		(legacy_teardrops no)
	)
	(paper "A4")
	(title_block
		(title "03242023_DA0F0TMBIJ0_F0T_Motherboard_J_brd_V01_OCP.brd")
		(comment 1 "Grand Teton / footprints 4405-4406 of 6105")
	)
	(layers
		(0 "F.Cu" signal "TOP")
		(4 "In1.Cu" signal "GND")
		(6 "In2.Cu" signal "IN1")
		(8 "In3.Cu" signal "GND1")
		(10 "In4.Cu" signal "IN2")
		(12 "In5.Cu" signal "GND2")
		(14 "In6.Cu" signal "IN3")
		(16 "In7.Cu" signal "GND3")
		(18 "In8.Cu" signal "VCC")
		(20 "In9.Cu" signal "VCC1")
		(22 "In10.Cu" signal "GND4")
		(24 "In11.Cu" signal "IN4")
		(26 "In12.Cu" signal "GND5")
		(28 "In13.Cu" signal "IN5")
		(30 "In14.Cu" signal "GND6")
		(32 "In15.Cu" signal "IN6")
		(34 "In16.Cu" signal "GND7")
		(2 "B.Cu" signal "BOTTOM")
		(9 "F.Adhes" user "F.Adhesive")
		(11 "B.Adhes" user "B.Adhesive")
		(13 "F.Paste" user "Package Geometry/Pastemask Top")
		(15 "B.Paste" user "Package Geometry/Pastemask Bottom")
		(5 "F.SilkS" user "Ref Des/Silkscreen Top")
		(7 "B.SilkS" user "Ref Des/Silkscreen Bottom")
		(1 "F.Mask" user "Board Geometry/Soldermask Top")
		(3 "B.Mask" user "Board Geometry/Soldermask Bottom")
		(17 "Dwgs.User" user "User.Drawings")
		(19 "Cmts.User" user "User.Comments")
		(21 "Eco1.User" user "User.Eco1")
		(23 "Eco2.User" user "User.Eco2")
		(25 "Edge.Cuts" user "Board Geometry/Outline")
		(27 "Margin" user)
		(31 "F.CrtYd" user "Package Geometry/Place Bound Top")
		(29 "B.CrtYd" user "Package Geometry/Place Bound Bottom")
		(35 "F.Fab" user "Ref Des/Assembly Top")
		(33 "B.Fab" user "Ref Des/Assembly Bottom")
	)
	(footprint ""
		(layer "B.Cu")
		(at 327.060814 -28.84297 -90)
		(property "Reference" "R1461"
			(at 0 0 90)
			(layer "B.SilkS")
			(hide yes)
			(effects
				(font
					(size 1.27 1.27)
				)
				(justify mirror)
			)
		)
		(property "Value" ""
			(at 0 0 90)
			(layer "B.Fab")
			(effects
				(font
					(size 1.27 1.27)
				)
				(justify mirror)
			)
		)
		(duplicate_pad_numbers_are_jumpers no)
		(fp_line
			(start -0.7874 0.4064)
			(end 0.7874 0.4064)
			(stroke
				(width 0.1524)
				(type default)
			)
			(layer "B.SilkS")
		)
		(fp_line
			(start 0.7874 0.4064)
			(end 0.7874 -0.4064)
			(stroke
				(width 0.1524)
				(type default)
			)
			(layer "B.SilkS")
		)
		(fp_line
			(start -0.7874 -0.4064)
			(end -0.7874 0.4064)
			(stroke
				(width 0.1524)
				(type default)
			)
			(layer "B.SilkS")
		)
		(fp_line
			(start 0.7874 -0.4064)
			(end -0.7874 -0.4064)
			(stroke
				(width 0.1524)
				(type default)
			)
			(layer "B.SilkS")
		)
		(fp_line
			(start -0.67945 0.3048)
			(end -0.120396 0.3048)
			(stroke
				(width 0.1)
				(type default)
			)
			(layer "B.Fab")
		)
		(fp_line
			(start -0.120396 0.3048)
			(end -0.120396 0.2794)
			(stroke
				(width 0.1)
				(type default)
			)
			(layer "B.Fab")
		)
		(fp_line
			(start 0.12065 0.3048)
			(end 0.67945 0.3048)
			(stroke
				(width 0.1)
				(type default)
			)
			(layer "B.Fab")
		)
		(fp_line
			(start 0.67945 0.3048)
			(end 0.67945 -0.305054)
			(stroke
				(width 0.1)
				(type default)
			)
			(layer "B.Fab")
		)
		(fp_line
			(start -0.120396 0.2794)
			(end 0.12065 0.2794)
			(stroke
				(width 0.1)
				(type default)
			)
			(layer "B.Fab")
		)
		(fp_line
			(start 0.12065 0.2794)
			(end 0.12065 0.3048)
			(stroke
				(width 0.1)
				(type default)
			)
			(layer "B.Fab")
		)
		(fp_line
			(start -0.12065 -0.2794)
			(end -0.12065 -0.3048)
			(stroke
				(width 0.1)
				(type default)
			)
			(layer "B.Fab")
		)
		(fp_line
			(start 0.12065 -0.2794)
			(end -0.12065 -0.2794)
			(stroke
				(width 0.1)
				(type default)
			)
			(layer "B.Fab")
		)
		(fp_line
			(start -0.67945 -0.3048)
			(end -0.67945 0.3048)
			(stroke
				(width 0.1)
				(type default)
			)
			(layer "B.Fab")
		)
		(fp_line
			(start -0.12065 -0.3048)
			(end -0.67945 -0.3048)
			(stroke
				(width 0.1)
				(type default)
			)
			(layer "B.Fab")
		)
		(fp_line
			(start 0.12065 -0.305054)
			(end 0.12065 -0.2794)
			(stroke
				(width 0.1)
				(type default)
			)
			(layer "B.Fab")
		)
		(fp_line
			(start 0.67945 -0.305054)
			(end 0.12065 -0.305054)
			(stroke
				(width 0.1)
				(type default)
			)
			(layer "B.Fab")
		)
		(pad "1" smd circle
			(at 0.40005 0 90)
			(size 0 0)
			(layers "B.Cu" "B.Mask" "B.Paste")
			(net "FM_EUP_LOT6_N")
		)
		(pad "2" smd circle
			(at -0.40005 0 90)
			(size 0 0)
			(layers "B.Cu" "B.Mask" "B.Paste")
			(net "FM_SUSACK_N")
		)
	)
	(footprint ""
		(layer "B.Cu")
		(at 337.166712 -31.693358 90)
		(property "Reference" "R917"
			(at 0 0 90)
			(layer "B.SilkS")
			(hide yes)
			(effects
				(font
					(size 1.27 1.27)
				)
				(justify mirror)
			)
		)
		(property "Value" ""
			(at 0 0 90)
			(layer "B.Fab")
			(effects
				(font
					(size 1.27 1.27)
				)
				(justify mirror)
			)
		)
		(duplicate_pad_numbers_are_jumpers no)
		(fp_line
			(start 0.7874 -0.4064)
			(end -0.7874 -0.4064)
			(stroke
				(width 0.1524)
				(type default)
			)
			(layer "B.SilkS")
		)
		(fp_line
			(start -0.7874 -0.4064)
			(end -0.7874 0.4064)
			(stroke
				(width 0.1524)
				(type default)
			)
			(layer "B.SilkS")
		)
		(fp_line
			(start 0.7874 0.4064)
			(end 0.7874 -0.4064)
			(stroke
				(width 0.1524)
				(type default)
			)
			(layer "B.SilkS")
		)
		(fp_line
			(start -0.7874 0.4064)
			(end 0.7874 0.4064)
			(stroke
				(width 0.1524)
				(type default)
			)
			(layer "B.SilkS")
		)
		(fp_line
			(start 0.67945 -0.305054)
			(end 0.12065 -0.305054)
			(stroke
				(width 0.1)
				(type default)
			)
			(layer "B.Fab")
		)
		(fp_line
			(start 0.12065 -0.305054)
			(end 0.12065 -0.2794)
			(stroke
				(width 0.1)
				(type default)
			)
			(layer "B.Fab")
		)
		(fp_line
			(start -0.12065 -0.3048)
			(end -0.67945 -0.3048)
			(stroke
				(width 0.1)
				(type default)
			)
			(layer "B.Fab")
		)
		(fp_line
			(start -0.67945 -0.3048)
			(end -0.67945 0.3048)
			(stroke
				(width 0.1)
				(type default)
			)
			(layer "B.Fab")
		)
		(fp_line
			(start 0.12065 -0.2794)
			(end -0.12065 -0.2794)
			(stroke
				(width 0.1)
				(type default)
			)
			(layer "B.Fab")
		)
		(fp_line
			(start -0.12065 -0.2794)
			(end -0.12065 -0.3048)
			(stroke
				(width 0.1)
				(type default)
			)
			(layer "B.Fab")
		)
		(fp_line
			(start 0.12065 0.2794)
			(end 0.12065 0.3048)
			(stroke
				(width 0.1)
				(type default)
			)
			(layer "B.Fab")
		)
		(fp_line
			(start -0.120396 0.2794)
			(end 0.12065 0.2794)
			(stroke
				(width 0.1)
				(type default)
			)
			(layer "B.Fab")
		)
		(fp_line
			(start 0.67945 0.3048)
			(end 0.67945 -0.305054)
			(stroke
				(width 0.1)
				(type default)
			)
			(layer "B.Fab")
		)
		(fp_line
			(start 0.12065 0.3048)
			(end 0.67945 0.3048)
			(stroke
				(width 0.1)
				(type default)
			)
			(layer "B.Fab")
		)
		(fp_line
			(start -0.120396 0.3048)
			(end -0.120396 0.2794)
			(stroke
				(width 0.1)
				(type default)
			)
			(layer "B.Fab")
		)
		(fp_line
			(start -0.67945 0.3048)
			(end -0.120396 0.3048)
			(stroke
				(width 0.1)
				(type default)
			)
			(layer "B.Fab")
		)
		(pad "1" smd circle
			(at 0.40005 0 270)
			(size 0 0)
			(layers "B.Cu" "B.Mask" "B.Paste")
			(net "SPI_PCH_IO3")
		)
		(pad "2" smd circle
			(at -0.40005 0 270)
			(size 0 0)
			(layers "B.Cu" "B.Mask" "B.Paste")
			(net "SPI_SYS_HOLD_IO3")
		)
	)
)
